# BASEBOARD_FAB2 (Tioga Pass) — schematic netlist excerpt (pin names and nets, part order shuffled) for the footprints in the layout excerpt that follows; sources: Cadence DE-HDL packaged netlist, KiCad conversion of Wiwynn_Tioga_Pass_MB.brd

EU9M1  SLG55021  IC  pkg SM  page 198
  VCC  = P5V_STBY
  \on\  = FM_ENABLE_FAN_POWER
  SHDN_N  = P5V_STBY
  GND  = GND
  D  = P12V_STBY
  S  = P12V_FAN
  G  = P12V_FAN_SWITCH_G
  PG  = TP_SLG55021_P12V_FAN_8
  THPAD  = GND

C7P2  CAP  100UF 4V 20% X5R  pkg 0805  page 228 : A = PVDDQ_KLM ; B = GND
R9T3  RES  6.19K 1% CHIP  pkg 0402  page 181 : A = FM_P12V_HOTSWAP0_EN ; B = GND

(kicad_pcb
	(version 20260206)
	(generator "pcbnew")
	(generator_version "10.0")
	(general
		(thickness 1.6)
		(legacy_teardrops no)
	)
	(paper "A4")
	(title_block
		(title "Wiwynn_Tioga_Pass_MB.brd")
		(comment 1 "Tioga Pass / footprints 4498-4500 of 4770")
	)
	(layers
		(0 "F.Cu" signal "TOP")
		(4 "In1.Cu" signal "L2GND")
		(6 "In2.Cu" signal "L3")
		(8 "In3.Cu" signal "L4GND")
		(10 "In4.Cu" signal "L5")
		(12 "In5.Cu" signal "L6GND")
		(14 "In6.Cu" signal "L7VCC")
		(16 "In7.Cu" signal "L8VCC")
		(18 "In8.Cu" signal "L9GND")
		(20 "In9.Cu" signal "L10")
		(22 "In10.Cu" signal "L11GND")
		(24 "In11.Cu" signal "L12")
		(26 "In12.Cu" signal "L13GND")
		(2 "B.Cu" signal "BOTTOM")
		(9 "F.Adhes" user "F.Adhesive")
		(11 "B.Adhes" user "B.Adhesive")
		(13 "F.Paste" user "Package Geometry/Pastemask Top")
		(15 "B.Paste" user "Package Geometry/Pastemask Bottom")
		(5 "F.SilkS" user "Ref Des/Silkscreen Top")
		(7 "B.SilkS" user "Ref Des/Silkscreen Bottom")
		(1 "F.Mask" user "Board Geometry/Soldermask Top")
		(3 "B.Mask" user "Board Geometry/Soldermask Bottom")
		(17 "Dwgs.User" user "User.Drawings")
		(19 "Cmts.User" user "User.Comments")
		(21 "Eco1.User" user "User.Eco1")
		(23 "Eco2.User" user "User.Eco2")
		(25 "Edge.Cuts" user "Board Geometry/Outline")
		(27 "Margin" user)
		(31 "F.CrtYd" user "Package Geometry/Place Bound Top")
		(29 "B.CrtYd" user "Package Geometry/Place Bound Bottom")
		(35 "F.Fab" user "Ref Des/Assembly Top")
		(33 "B.Fab" user "Ref Des/Assembly Bottom")
	)
	(footprint ""
		(layer "B.Cu")
		(at 7.2898 -122.936)
		(property "Reference" "EU9M1"
			(at 4.5212 -0.35433 0)
			(unlocked yes)
			(layer "B.SilkS")
			(effects
				(font
					(size 0.7874 0.5842)
					(thickness 0.1524)
				)
				(justify left mirror)
			)
		)
		(property "Value" ""
			(at 0 0 0)
			(layer "B.Fab")
			(effects
				(font
					(size 1.27 1.27)
				)
				(justify mirror)
			)
		)
		(duplicate_pad_numbers_are_jumpers no)
		(fp_circle
			(center 0.702056 -0.595376)
			(end 0.829056 -0.595376)
			(stroke
				(width 0.254)
				(type default)
			)
			(fill no)
			(layer "B.SilkS")
		)
		(fp_rect
			(start -1.4732 1.549908)
			(end -0.5842 -0.050292)
			(stroke
				(width 0)
				(type default)
			)
			(fill yes)
			(layer "B.Paste")
		)
		(fp_rect
			(start -2.078736 1.799844)
			(end 0.021336 -0.300228)
			(stroke
				(width 0)
				(type default)
			)
			(fill no)
			(layer "B.CrtYd")
		)
		(fp_line
			(start -2.078736 -0.300228)
			(end -2.078736 1.799844)
			(stroke
				(width 0.1)
				(type default)
			)
			(layer "B.Fab")
		)
		(fp_line
			(start -2.078736 1.799844)
			(end 0.021336 1.799844)
			(stroke
				(width 0.1)
				(type default)
			)
			(layer "B.Fab")
		)
		(fp_line
			(start 0.021336 -0.300228)
			(end -2.078736 -0.300228)
			(stroke
				(width 0.1)
				(type default)
			)
			(layer "B.Fab")
		)
		(fp_line
			(start 0.021336 1.799844)
			(end 0.021336 -0.300228)
			(stroke
				(width 0.1)
				(type default)
			)
			(layer "B.Fab")
		)
		(fp_circle
			(center 0.702056 -0.595376)
			(end 0.829056 -0.595376)
			(stroke
				(width 0.254)
				(type default)
			)
			(fill no)
			(layer "B.Fab")
		)
		(pad "1" smd rect
			(at 0 0 180)
			(size 0.6604 0.3048)
			(layers "B.Cu" "B.Mask" "B.Paste")
			(net "P5V_STBY")
		)
		(pad "2" smd rect
			(at 0 0.499872 180)
			(size 0.6604 0.3048)
			(layers "B.Cu" "B.Mask" "B.Paste")
			(net "FM_ENABLE_FAN_POWER")
		)
		(pad "3" smd rect
			(at 0 0.999744 180)
			(size 0.6604 0.3048)
			(layers "B.Cu" "B.Mask" "B.Paste")
			(net "P5V_STBY")
		)
		(pad "4" smd rect
			(at 0 1.499616 180)
			(size 0.6604 0.3048)
			(layers "B.Cu" "B.Mask" "B.Paste")
			(net "GND")
		)
		(pad "5" smd rect
			(at -2.0574 1.499616 180)
			(size 0.6604 0.3048)
			(layers "B.Cu" "B.Mask" "B.Paste")
			(net "P12V_STBY")
		)
		(pad "6" smd rect
			(at -2.0574 0.999744 180)
			(size 0.6604 0.3048)
			(layers "B.Cu" "B.Mask" "B.Paste")
			(net "P12V_FAN")
		)
		(pad "7" smd rect
			(at -2.0574 0.499872 180)
			(size 0.6604 0.3048)
			(layers "B.Cu" "B.Mask" "B.Paste")
			(net "P12V_FAN_SWITCH_G")
		)
		(pad "8" smd rect
			(at -2.0574 0 180)
			(size 0.6604 0.3048)
			(layers "B.Cu" "B.Mask" "B.Paste")
			(net "TP_SLG55021_P12V_FAN_8")
		)
		(pad "9" smd rect
			(at -1.0287 0.749808 180)
			(size 0.889 1.6002)
			(layers "B.Cu" "B.Mask" "B.Paste")
			(net "GND")
		)
	)
	(footprint ""
		(layer "B.Cu")
		(at 24.692356 -31.679896 -90)
		(property "Reference" "R9T3"
			(at 0 0 90)
			(layer "B.SilkS")
			(hide yes)
			(effects
				(font
					(size 1.27 1.27)
				)
				(justify mirror)
			)
		)
		(property "Value" ""
			(at 0 0 90)
			(layer "B.Fab")
			(effects
				(font
					(size 1.27 1.27)
				)
				(justify mirror)
			)
		)
		(duplicate_pad_numbers_are_jumpers no)
		(fp_rect
			(start -0.2794 -0.1016)
			(end 0.2794 0.9906)
			(stroke
				(width 0)
				(type default)
			)
			(fill no)
			(layer "B.CrtYd")
		)
		(fp_line
			(start -0.2794 0.9906)
			(end -0.2794 -0.1016)
			(stroke
				(width 0.1)
				(type default)
			)
			(layer "B.Fab")
		)
		(fp_line
			(start 0.2794 0.9906)
			(end -0.2794 0.9906)
			(stroke
				(width 0.1)
				(type default)
			)
			(layer "B.Fab")
		)
		(fp_line
			(start -0.2794 -0.1016)
			(end 0.2794 -0.1016)
			(stroke
				(width 0.1)
				(type default)
			)
			(layer "B.Fab")
		)
		(fp_line
			(start 0.2794 -0.1016)
			(end 0.2794 0.9906)
			(stroke
				(width 0.1)
				(type default)
			)
			(layer "B.Fab")
		)
		(pad "1" smd rect
			(at 0 0 90)
			(size 0.508 0.508)
			(layers "B.Cu" "B.Mask" "B.Paste")
			(net "FM_P12V_HOTSWAP0_EN")
		)
		(pad "2" smd rect
			(at 0 0.889 90)
			(size 0.508 0.508)
			(layers "B.Cu" "B.Mask" "B.Paste")
			(net "GND")
		)
		(zone
			(layer "B.Cu")
			(hatch none 0.5)
			(connect_pads
				(clearance 0)
			)
			(min_thickness 0.25)
			(keepout
				(tracks allowed)
				(vias not_allowed)
				(pads allowed)
				(copperpour not_allowed)
				(footprints allowed)
			)
			(placement
				(enabled no)
				(sheetname "")
			)
			(fill
				(thermal_gap 0.5)
				(thermal_bridge_width 0.5)
				(island_removal_mode 0)
			)
			(polygon
				(pts
					(xy 24.438356 -31.933896) (xy 24.057356 -31.933896) (xy 24.057356 -31.425896) (xy 24.438356 -31.425896)
				)
			)
		)
		(zone
			(layer "B.Cu")
			(hatch none 0.5)
			(connect_pads
				(clearance 0)
			)
			(min_thickness 0.25)
			(keepout
				(tracks not_allowed)
				(vias allowed)
				(pads allowed)
				(copperpour not_allowed)
				(footprints allowed)
			)
			(placement
				(enabled no)
				(sheetname "")
			)
			(fill
				(thermal_gap 0.5)
				(thermal_bridge_width 0.5)
				(island_removal_mode 0)
			)
			(polygon
				(pts
					(xy 24.438356 -31.933896) (xy 24.057356 -31.933896) (xy 24.057356 -31.425896) (xy 24.438356 -31.425896)
				)
			)
		)
	)
	(footprint ""
		(layer "B.Cu")
		(at 108.051854 -85.06714)
		(property "Reference" "C7P2"
			(at 0 0 0)
			(layer "B.SilkS")
			(hide yes)
			(effects
				(font
					(size 1.27 1.27)
				)
				(justify mirror)
			)
		)
		(property "Value" ""
			(at 0 0 0)
			(layer "B.Fab")
			(effects
				(font
					(size 1.27 1.27)
				)
				(justify mirror)
			)
		)
		(duplicate_pad_numbers_are_jumpers no)
		(fp_poly
			(pts
				(xy 0.7239 -0.2159) (xy -0.7239 -0.2159) (xy -0.7239 1.9939) (xy 0.7239 1.9939)
			)
			(stroke
				(width 0)
				(type default)
			)
			(fill no)
			(layer "B.CrtYd")
		)
		(fp_line
			(start -0.7239 -0.2159)
			(end 0.7239 -0.2159)
			(stroke
				(width 0.1)
				(type default)
			)
			(layer "B.Fab")
		)
		(fp_line
			(start -0.7239 1.9939)
			(end -0.7239 -0.2159)
			(stroke
				(width 0.1)
				(type default)
			)
			(layer "B.Fab")
		)
		(fp_line
			(start 0.7239 -0.2159)
			(end 0.7239 1.9939)
			(stroke
				(width 0.1)
				(type default)
			)
			(layer "B.Fab")
		)
		(fp_line
			(start 0.7239 1.9939)
			(end -0.7239 1.9939)
			(stroke
				(width 0.1)
				(type default)
			)
			(layer "B.Fab")
		)
		(pad "1" smd rect
			(at 0 0 180)
			(size 1.27 1.016)
			(layers "B.Cu" "B.Mask" "B.Paste")
			(net "PVDDQ_KLM")
		)
		(pad "2" smd rect
			(at 0 1.778 180)
			(size 1.27 1.016)
			(layers "B.Cu" "B.Mask" "B.Paste")
			(net "GND")
		)
		(zone
			(layer "B.Cu")
			(hatch none 0.5)
			(connect_pads
				(clearance 0)
			)
			(min_thickness 0.25)
			(keepout
				(tracks not_allowed)
				(vias allowed)
				(pads allowed)
				(copperpour not_allowed)
				(footprints allowed)
			)
			(placement
				(enabled no)
				(sheetname "")
			)
			(fill
				(thermal_gap 0.5)
				(thermal_bridge_width 0.5)
				(island_removal_mode 0)
			)
			(polygon
				(pts
					(xy 108.686854 -84.55914) (xy 107.416854 -84.55914) (xy 107.416854 -83.79714) (xy 108.686854 -83.79714)
				)
			)
		)
	)
)
